# BASEBOARD_FAB2 (Tioga Pass) — schematic netlist excerpt (pin names and nets, part order shuffled) for the footprints in the layout excerpt that follows; sources: Cadence DE-HDL packaged netlist, KiCad conversion of Wiwynn_Tioga_Pass_MB.brd

CT26  CAP  1000PF 50V 10% X7R  pkg 0402LF  page 207 : A = A_TSENSE_PVCCIN_CPU1 ; B = GND
C5P32  CAP  47UF 4V 20% X6S  pkg 0805  page 42 : A = PVCCIN_CPU0 ; B = GND
C3T11  CAP  4.7UF 6.3V 10% X6S  pkg 0603  page 231 : A = VR_VB_PVPP_ABC ; B = AGND_PVPP_ABC

(kicad_pcb
	(version 20260206)
	(generator "pcbnew")
	(generator_version "10.0")
	(general
		(thickness 1.6)
		(legacy_teardrops no)
	)
	(paper "A4")
	(title_block
		(title "Wiwynn_Tioga_Pass_MB.brd")
		(comment 1 "Tioga Pass / footprints 3553-3555 of 4770")
	)
	(layers
		(0 "F.Cu" signal "TOP")
		(4 "In1.Cu" signal "L2GND")
		(6 "In2.Cu" signal "L3")
		(8 "In3.Cu" signal "L4GND")
		(10 "In4.Cu" signal "L5")
		(12 "In5.Cu" signal "L6GND")
		(14 "In6.Cu" signal "L7VCC")
		(16 "In7.Cu" signal "L8VCC")
		(18 "In8.Cu" signal "L9GND")
		(20 "In9.Cu" signal "L10")
		(22 "In10.Cu" signal "L11GND")
		(24 "In11.Cu" signal "L12")
		(26 "In12.Cu" signal "L13GND")
		(2 "B.Cu" signal "BOTTOM")
		(9 "F.Adhes" user "F.Adhesive")
		(11 "B.Adhes" user "B.Adhesive")
		(13 "F.Paste" user "Package Geometry/Pastemask Top")
		(15 "B.Paste" user "Package Geometry/Pastemask Bottom")
		(5 "F.SilkS" user "Ref Des/Silkscreen Top")
		(7 "B.SilkS" user "Ref Des/Silkscreen Bottom")
		(1 "F.Mask" user "Board Geometry/Soldermask Top")
		(3 "B.Mask" user "Board Geometry/Soldermask Bottom")
		(17 "Dwgs.User" user "User.Drawings")
		(19 "Cmts.User" user "User.Comments")
		(21 "Eco1.User" user "User.Eco1")
		(23 "Eco2.User" user "User.Eco2")
		(25 "Edge.Cuts" user "Board Geometry/Outline")
		(27 "Margin" user)
		(31 "F.CrtYd" user "Package Geometry/Place Bound Top")
		(29 "B.CrtYd" user "Package Geometry/Place Bound Bottom")
		(35 "F.Fab" user "Ref Des/Assembly Top")
		(33 "B.Fab" user "Ref Des/Assembly Bottom")
	)
	(footprint ""
		(layer "B.Cu")
		(at 267.692886 -73.51014)
		(property "Reference" "C5P32"
			(at 0 0 0)
			(layer "B.SilkS")
			(hide yes)
			(effects
				(font
					(size 1.27 1.27)
				)
				(justify mirror)
			)
		)
		(property "Value" ""
			(at 0 0 0)
			(layer "B.Fab")
			(effects
				(font
					(size 1.27 1.27)
				)
				(justify mirror)
			)
		)
		(duplicate_pad_numbers_are_jumpers no)
		(fp_poly
			(pts
				(xy 0.7239 -0.2159) (xy -0.7239 -0.2159) (xy -0.7239 1.9939) (xy 0.7239 1.9939)
			)
			(stroke
				(width 0)
				(type default)
			)
			(fill no)
			(layer "B.CrtYd")
		)
		(fp_line
			(start -0.7239 -0.2159)
			(end 0.7239 -0.2159)
			(stroke
				(width 0.1)
				(type default)
			)
			(layer "B.Fab")
		)
		(fp_line
			(start -0.7239 1.9939)
			(end -0.7239 -0.2159)
			(stroke
				(width 0.1)
				(type default)
			)
			(layer "B.Fab")
		)
		(fp_line
			(start 0.7239 -0.2159)
			(end 0.7239 1.9939)
			(stroke
				(width 0.1)
				(type default)
			)
			(layer "B.Fab")
		)
		(fp_line
			(start 0.7239 1.9939)
			(end -0.7239 1.9939)
			(stroke
				(width 0.1)
				(type default)
			)
			(layer "B.Fab")
		)
		(pad "1" smd rect
			(at 0 0 180)
			(size 1.27 1.016)
			(layers "B.Cu" "B.Mask" "B.Paste")
			(net "PVCCIN_CPU0")
		)
		(pad "2" smd rect
			(at 0 1.778 180)
			(size 1.27 1.016)
			(layers "B.Cu" "B.Mask" "B.Paste")
			(net "GND")
		)
		(zone
			(layer "B.Cu")
			(hatch none 0.5)
			(connect_pads
				(clearance 0)
			)
			(min_thickness 0.25)
			(keepout
				(tracks not_allowed)
				(vias allowed)
				(pads allowed)
				(copperpour not_allowed)
				(footprints allowed)
			)
			(placement
				(enabled no)
				(sheetname "")
			)
			(fill
				(thermal_gap 0.5)
				(thermal_bridge_width 0.5)
				(island_removal_mode 0)
			)
			(polygon
				(pts
					(xy 268.327886 -73.00214) (xy 267.057886 -73.00214) (xy 267.057886 -72.24014) (xy 268.327886 -72.24014)
				)
			)
		)
	)
	(footprint ""
		(layer "B.Cu")
		(at 30.988 -64.262 180)
		(property "Reference" "CT26"
			(at 0.8382 -0.84963 180)
			(unlocked yes)
			(layer "B.SilkS")
			(effects
				(font
					(size 0.7874 0.5842)
					(thickness 0.1524)
				)
				(justify left mirror)
			)
		)
		(property "Value" ""
			(at 0 0 0)
			(layer "B.Fab")
			(effects
				(font
					(size 1.27 1.27)
				)
				(justify mirror)
			)
		)
		(duplicate_pad_numbers_are_jumpers no)
		(fp_poly
			(pts
				(xy -0.3048 -0.1016) (xy -0.3048 0.9906) (xy 0.3048 0.9906) (xy 0.3048 -0.1016)
			)
			(stroke
				(width 0)
				(type default)
			)
			(fill no)
			(layer "B.CrtYd")
		)
		(fp_line
			(start 0.3048 0.9906)
			(end -0.3048 0.9906)
			(stroke
				(width 0.1)
				(type default)
			)
			(layer "B.Fab")
		)
		(fp_line
			(start 0.3048 -0.1016)
			(end 0.3048 0.9906)
			(stroke
				(width 0.1)
				(type default)
			)
			(layer "B.Fab")
		)
		(fp_line
			(start -0.3048 0.9906)
			(end -0.3048 -0.1016)
			(stroke
				(width 0.1)
				(type default)
			)
			(layer "B.Fab")
		)
		(fp_line
			(start -0.3048 -0.1016)
			(end 0.3048 -0.1016)
			(stroke
				(width 0.1)
				(type default)
			)
			(layer "B.Fab")
		)
		(pad "1" smd rect
			(at 0 0)
			(size 0.508 0.508)
			(layers "B.Cu" "B.Mask" "B.Paste")
			(net "A_TSENSE_PVCCIN_CPU1")
		)
		(pad "2" smd rect
			(at 0 0.889)
			(size 0.508 0.508)
			(layers "B.Cu" "B.Mask" "B.Paste")
			(net "GND")
		)
		(zone
			(layer "B.Cu")
			(hatch none 0.5)
			(connect_pads
				(clearance 0)
			)
			(min_thickness 0.25)
			(keepout
				(tracks not_allowed)
				(vias allowed)
				(pads allowed)
				(copperpour not_allowed)
				(footprints allowed)
			)
			(placement
				(enabled no)
				(sheetname "")
			)
			(fill
				(thermal_gap 0.5)
				(thermal_bridge_width 0.5)
				(island_removal_mode 0)
			)
			(polygon
				(pts
					(xy 30.734 -64.897) (xy 31.242 -64.897) (xy 31.242 -64.516) (xy 30.734 -64.516)
				)
			)
		)
		(zone
			(layer "B.Cu")
			(hatch none 0.5)
			(connect_pads
				(clearance 0)
			)
			(min_thickness 0.25)
			(keepout
				(tracks allowed)
				(vias not_allowed)
				(pads allowed)
				(copperpour not_allowed)
				(footprints allowed)
			)
			(placement
				(enabled no)
				(sheetname "")
			)
			(fill
				(thermal_gap 0.5)
				(thermal_bridge_width 0.5)
				(island_removal_mode 0)
			)
			(polygon
				(pts
					(xy 30.734 -64.516) (xy 31.242 -64.516) (xy 31.242 -64.897) (xy 30.734 -64.897)
				)
			)
		)
	)
	(footprint ""
		(layer "B.Cu")
		(at 339.979 -27.178)
		(property "Reference" "C3T11"
			(at 0 0 0)
			(layer "B.SilkS")
			(hide yes)
			(effects
				(font
					(size 1.27 1.27)
				)
				(justify mirror)
			)
		)
		(property "Value" ""
			(at 0 0 0)
			(layer "B.Fab")
			(effects
				(font
					(size 1.27 1.27)
				)
				(justify mirror)
			)
		)
		(duplicate_pad_numbers_are_jumpers no)
		(fp_rect
			(start 0.4953 1.6002)
			(end -0.4953 -0.2032)
			(stroke
				(width 0)
				(type default)
			)
			(fill no)
			(layer "B.CrtYd")
		)
		(fp_line
			(start -0.4953 -0.2032)
			(end -0.4953 1.6002)
			(stroke
				(width 0.1)
				(type default)
			)
			(layer "B.Fab")
		)
		(fp_line
			(start -0.4953 1.6002)
			(end 0.4953 1.6002)
			(stroke
				(width 0.1)
				(type default)
			)
			(layer "B.Fab")
		)
		(fp_line
			(start 0.4953 -0.2032)
			(end -0.4953 -0.2032)
			(stroke
				(width 0.1)
				(type default)
			)
			(layer "B.Fab")
		)
		(fp_line
			(start 0.4953 1.6002)
			(end 0.4953 -0.2032)
			(stroke
				(width 0.1)
				(type default)
			)
			(layer "B.Fab")
		)
		(pad "1" smd rect
			(at 0 0 180)
			(size 0.762 0.889)
			(layers "B.Cu" "B.Mask" "B.Paste")
			(net "VR_VB_PVPP_ABC")
		)
		(pad "2" smd rect
			(at 0 1.397 180)
			(size 0.762 0.889)
			(layers "B.Cu" "B.Mask" "B.Paste")
			(net "AGND_PVPP_ABC")
		)
		(zone
			(layer "B.Cu")
			(hatch none 0.5)
			(connect_pads
				(clearance 0)
			)
			(min_thickness 0.25)
			(keepout
				(tracks not_allowed)
				(vias allowed)
				(pads allowed)
				(copperpour not_allowed)
				(footprints allowed)
			)
			(placement
				(enabled no)
				(sheetname "")
			)
			(fill
				(thermal_gap 0.5)
				(thermal_bridge_width 0.5)
				(island_removal_mode 0)
			)
			(polygon
				(pts
					(xy 340.36 -26.2255) (xy 340.36 -26.7335) (xy 339.598 -26.7335) (xy 339.598 -26.2255)
				)
			)
		)
	)
)
